# SCM (Grand Teton) — schematic netlist excerpt (pin names and nets, part order shuffled) for the footprints in the layout excerpt that follows; sources: Cadence DE-HDL packaged netlist, KiCad conversion of 12092022_DA0F0TMDCD0_F0T_Management_Board_D_brd_V3_OCP.brd

R665  Q_RES  1K 1% EMPTY  pkg 0402LF  page 21 : A = SPI_BMC_BT_WP0_N_R ; B = GND
R81  Q_RES  4.7K 1% CHIP  pkg 0402LF  page 11 : A = P3V3_AUX ; B = PWR_BTN_BMC_N

(kicad_pcb
	(version 20260206)
	(generator "pcbnew")
	(generator_version "10.0")
	(general
		(thickness 1.6)
		(legacy_teardrops no)
	)
	(paper "A4")
	(title_block
		(title "12092022_DA0F0TMDCD0_F0T_Management_Board_D_brd_V3_OCP.brd")
		(comment 1 "Grand Teton / footprints 340-341 of 1440")
	)
	(layers
		(0 "F.Cu" signal "TOP")
		(4 "In1.Cu" signal "GND")
		(6 "In2.Cu" signal "IN1")
		(8 "In3.Cu" signal "GND1")
		(10 "In4.Cu" signal "IN2")
		(12 "In5.Cu" signal "VCC")
		(14 "In6.Cu" signal "VCC1")
		(16 "In7.Cu" signal "IN3")
		(18 "In8.Cu" signal "GND2")
		(20 "In9.Cu" signal "IN4")
		(22 "In10.Cu" signal "GND3")
		(2 "B.Cu" signal "BOTTOM")
		(9 "F.Adhes" user "F.Adhesive")
		(11 "B.Adhes" user "B.Adhesive")
		(13 "F.Paste" user "Package Geometry/Pastemask Top")
		(15 "B.Paste" user "Package Geometry/Pastemask Bottom")
		(5 "F.SilkS" user "Ref Des/Silkscreen Top")
		(7 "B.SilkS" user "Ref Des/Silkscreen Bottom")
		(1 "F.Mask" user "Board Geometry/Soldermask Top")
		(3 "B.Mask" user "Board Geometry/Soldermask Bottom")
		(17 "Dwgs.User" user "User.Drawings")
		(19 "Cmts.User" user "User.Comments")
		(21 "Eco1.User" user "User.Eco1")
		(23 "Eco2.User" user "User.Eco2")
		(25 "Edge.Cuts" user "Board Geometry/Outline")
		(27 "Margin" user)
		(31 "F.CrtYd" user "Package Geometry/Place Bound Top")
		(29 "B.CrtYd" user "Package Geometry/Place Bound Bottom")
		(35 "F.Fab" user "Ref Des/Assembly Top")
		(33 "B.Fab" user "Ref Des/Assembly Bottom")
	)
	(footprint ""
		(layer "F.Cu")
		(at 30.5562 -87.9856 180)
		(property "Reference" "R81"
			(at 0 0 180)
			(layer "F.SilkS")
			(hide yes)
			(effects
				(font
					(size 1.27 1.27)
				)
			)
		)
		(property "Value" ""
			(at 0 0 180)
			(layer "F.Fab")
			(effects
				(font
					(size 1.27 1.27)
				)
			)
		)
		(duplicate_pad_numbers_are_jumpers no)
		(fp_line
			(start 0.7874 0.4064)
			(end -0.7874 0.4064)
			(stroke
				(width 0.1524)
				(type default)
			)
			(layer "F.SilkS")
		)
		(fp_line
			(start 0.7874 -0.4064)
			(end 0.7874 0.4064)
			(stroke
				(width 0.1524)
				(type default)
			)
			(layer "F.SilkS")
		)
		(fp_line
			(start -0.7874 0.4064)
			(end -0.7874 -0.4064)
			(stroke
				(width 0.1524)
				(type default)
			)
			(layer "F.SilkS")
		)
		(fp_line
			(start -0.7874 -0.4064)
			(end 0.7874 -0.4064)
			(stroke
				(width 0.1524)
				(type default)
			)
			(layer "F.SilkS")
		)
		(fp_line
			(start 0.67945 0.3048)
			(end 0.120396 0.3048)
			(stroke
				(width 0.1)
				(type default)
			)
			(layer "F.Fab")
		)
		(fp_line
			(start 0.67945 -0.3048)
			(end 0.67945 0.3048)
			(stroke
				(width 0.1)
				(type default)
			)
			(layer "F.Fab")
		)
		(fp_line
			(start 0.12065 -0.2794)
			(end 0.12065 -0.3048)
			(stroke
				(width 0.1)
				(type default)
			)
			(layer "F.Fab")
		)
		(fp_line
			(start 0.12065 -0.3048)
			(end 0.67945 -0.3048)
			(stroke
				(width 0.1)
				(type default)
			)
			(layer "F.Fab")
		)
		(fp_line
			(start 0.120396 0.3048)
			(end 0.120396 0.2794)
			(stroke
				(width 0.1)
				(type default)
			)
			(layer "F.Fab")
		)
		(fp_line
			(start 0.120396 0.2794)
			(end -0.12065 0.2794)
			(stroke
				(width 0.1)
				(type default)
			)
			(layer "F.Fab")
		)
		(fp_line
			(start -0.12065 0.3048)
			(end -0.67945 0.3048)
			(stroke
				(width 0.1)
				(type default)
			)
			(layer "F.Fab")
		)
		(fp_line
			(start -0.12065 0.2794)
			(end -0.12065 0.3048)
			(stroke
				(width 0.1)
				(type default)
			)
			(layer "F.Fab")
		)
		(fp_line
			(start -0.12065 -0.2794)
			(end 0.12065 -0.2794)
			(stroke
				(width 0.1)
				(type default)
			)
			(layer "F.Fab")
		)
		(fp_line
			(start -0.12065 -0.305054)
			(end -0.12065 -0.2794)
			(stroke
				(width 0.1)
				(type default)
			)
			(layer "F.Fab")
		)
		(fp_line
			(start -0.67945 0.3048)
			(end -0.67945 -0.305054)
			(stroke
				(width 0.1)
				(type default)
			)
			(layer "F.Fab")
		)
		(fp_line
			(start -0.67945 -0.305054)
			(end -0.12065 -0.305054)
			(stroke
				(width 0.1)
				(type default)
			)
			(layer "F.Fab")
		)
		(pad "1" smd circle
			(at -0.40005 0 180)
			(size 0 0)
			(layers "F.Cu" "F.Mask" "F.Paste")
			(net "P3V3_AUX")
		)
		(pad "2" smd circle
			(at 0.40005 0 180)
			(size 0 0)
			(layers "F.Cu" "F.Mask" "F.Paste")
			(net "PWR_BTN_BMC_N")
		)
	)
	(footprint ""
		(layer "F.Cu")
		(at 16.5354 -70.739 -90)
		(property "Reference" "R665"
			(at 0 0 270)
			(layer "F.SilkS")
			(hide yes)
			(effects
				(font
					(size 1.27 1.27)
				)
			)
		)
		(property "Value" ""
			(at 0 0 270)
			(layer "F.Fab")
			(effects
				(font
					(size 1.27 1.27)
				)
			)
		)
		(duplicate_pad_numbers_are_jumpers no)
		(fp_line
			(start -0.7874 0.4064)
			(end -0.7874 -0.4064)
			(stroke
				(width 0.1524)
				(type default)
			)
			(layer "F.SilkS")
		)
		(fp_line
			(start 0.7874 0.4064)
			(end -0.7874 0.4064)
			(stroke
				(width 0.1524)
				(type default)
			)
			(layer "F.SilkS")
		)
		(fp_line
			(start -0.7874 -0.4064)
			(end 0.7874 -0.4064)
			(stroke
				(width 0.1524)
				(type default)
			)
			(layer "F.SilkS")
		)
		(fp_line
			(start 0.7874 -0.4064)
			(end 0.7874 0.4064)
			(stroke
				(width 0.1524)
				(type default)
			)
			(layer "F.SilkS")
		)
		(fp_line
			(start -0.67945 0.3048)
			(end -0.67945 -0.305054)
			(stroke
				(width 0.1)
				(type default)
			)
			(layer "F.Fab")
		)
		(fp_line
			(start -0.12065 0.3048)
			(end -0.67945 0.3048)
			(stroke
				(width 0.1)
				(type default)
			)
			(layer "F.Fab")
		)
		(fp_line
			(start 0.120396 0.3048)
			(end 0.120396 0.2794)
			(stroke
				(width 0.1)
				(type default)
			)
			(layer "F.Fab")
		)
		(fp_line
			(start 0.67945 0.3048)
			(end 0.120396 0.3048)
			(stroke
				(width 0.1)
				(type default)
			)
			(layer "F.Fab")
		)
		(fp_line
			(start -0.12065 0.2794)
			(end -0.12065 0.3048)
			(stroke
				(width 0.1)
				(type default)
			)
			(layer "F.Fab")
		)
		(fp_line
			(start 0.120396 0.2794)
			(end -0.12065 0.2794)
			(stroke
				(width 0.1)
				(type default)
			)
			(layer "F.Fab")
		)
		(fp_line
			(start -0.12065 -0.2794)
			(end 0.12065 -0.2794)
			(stroke
				(width 0.1)
				(type default)
			)
			(layer "F.Fab")
		)
		(fp_line
			(start 0.12065 -0.2794)
			(end 0.12065 -0.3048)
			(stroke
				(width 0.1)
				(type default)
			)
			(layer "F.Fab")
		)
		(fp_line
			(start 0.12065 -0.3048)
			(end 0.67945 -0.3048)
			(stroke
				(width 0.1)
				(type default)
			)
			(layer "F.Fab")
		)
		(fp_line
			(start 0.67945 -0.3048)
			(end 0.67945 0.3048)
			(stroke
				(width 0.1)
				(type default)
			)
			(layer "F.Fab")
		)
		(fp_line
			(start -0.67945 -0.305054)
			(end -0.12065 -0.305054)
			(stroke
				(width 0.1)
				(type default)
			)
			(layer "F.Fab")
		)
		(fp_line
			(start -0.12065 -0.305054)
			(end -0.12065 -0.2794)
			(stroke
				(width 0.1)
				(type default)
			)
			(layer "F.Fab")
		)
		(pad "1" smd circle
			(at -0.40005 0 270)
			(size 0 0)
			(layers "F.Cu" "F.Mask" "F.Paste")
			(net "SPI_BMC_BT_WP0_N_R")
		)
		(pad "2" smd circle
			(at 0.40005 0 270)
			(size 0 0)
			(layers "F.Cu" "F.Mask" "F.Paste")
			(net "GND")
		)
	)
)
